(kicad_pcb
	(version 20260206)
	(generator "pcbnew")
	(generator_version "10.0")
	(general
		(thickness 1.6)
		(legacy_teardrops no)
	)
	(paper "A4")
	(title_block
		(title "riser — 13919-sa.brd")
		(comment 1 "Honey Badger (Wiwynn) / footprint 2 of 2 (CN1), pads 77-152 of 166")
	)
	(layers
		(0 "F.Cu" signal "TOP")
		(4 "In1.Cu" signal "L2VCC")
		(6 "In2.Cu" signal "L3GND")
		(2 "B.Cu" signal "BOTTOM")
		(9 "F.Adhes" user "F.Adhesive")
		(11 "B.Adhes" user "B.Adhesive")
		(13 "F.Paste" user "Package Geometry/Pastemask Top")
		(15 "B.Paste" user "Package Geometry/Pastemask Bottom")
		(5 "F.SilkS" user "Ref Des/Silkscreen Top")
		(7 "B.SilkS" user "Ref Des/Silkscreen Bottom")
		(1 "F.Mask" user "Board Geometry/Soldermask Top")
		(3 "B.Mask" user "Board Geometry/Soldermask Bottom")
		(17 "Dwgs.User" user "User.Drawings")
		(19 "Cmts.User" user "User.Comments")
		(21 "Eco1.User" user "User.Eco1")
		(23 "Eco2.User" user "User.Eco2")
		(25 "Edge.Cuts" user "Board Geometry/Outline")
		(27 "Margin" user)
		(31 "F.CrtYd" user "Package Geometry/Place Bound Top")
		(29 "B.CrtYd" user "Package Geometry/Place Bound Bottom")
		(35 "F.Fab" user "Ref Des/Assembly Top")
		(33 "B.Fab" user "Ref Des/Assembly Bottom")
	)
	(footprint ""
		(layer "F.Cu")
		(at 77.350112 -19.899884 180)
		(property "Reference" "CN1"
			(at 0 0 180)
			(layer "F.SilkS")
			(hide yes)
			(effects
				(font
					(size 1.27 1.27)
				)
			)
		)
		(property "Value" "PCISLT164-44-GP"
			(at -23.3172 -6.8961 180)
			(unlocked yes)
			(layer "F.Fab")
			(hide yes)
			(effects
				(font
					(size 1.016 1.016)
					(thickness 0.1524)
				)
			)
		)
		(property "Device Type" "AAA-PCI-066-K06"
			(at -23.3172 -8.4201 180)
			(unlocked yes)
			(layer "F.Fab")
			(hide yes)
			(effects
				(font
					(size 1.016 1.016)
					(thickness 0.1524)
				)
			)
		)
		(duplicate_pad_numbers_are_jumpers no)
		(pad "A75" thru_hole circle
			(at 64.34963 -1.24968 180)
			(size 1.0922 1.0922)
			(drill 0.7366)
			(layers "*.Cu" "*.Mask")
			(remove_unused_layers no)
			(net "GND")
			(clearance 0.1778)
			(thermal_gap 0.1778)
		)
		(pad "A76" thru_hole circle
			(at 65.35039 -3.24993 180)
			(size 1.0922 1.0922)
			(drill 0.7366)
			(layers "*.Cu" "*.Mask")
			(remove_unused_layers no)
			(net "GND")
			(clearance 0.1778)
			(thermal_gap 0.1778)
		)
		(pad "A77" thru_hole circle
			(at 66.34988 -1.24968 180)
			(size 1.0922 1.0922)
			(drill 0.7366)
			(layers "*.Cu" "*.Mask")
			(remove_unused_layers no)
			(net "P2E_CPU_ETH10G_RX_DP11")
			(clearance 0.1778)
			(thermal_gap 0.1778)
		)
		(pad "A78" thru_hole circle
			(at 67.34937 -3.24993 180)
			(size 1.0922 1.0922)
			(drill 0.7366)
			(layers "*.Cu" "*.Mask")
			(remove_unused_layers no)
			(net "P2E_CPU_ETH10G_RX_DN11")
			(clearance 0.1778)
			(thermal_gap 0.1778)
		)
		(pad "A79" thru_hole circle
			(at 68.35013 -1.24968 180)
			(size 1.0922 1.0922)
			(drill 0.7366)
			(layers "*.Cu" "*.Mask")
			(remove_unused_layers no)
			(net "GND")
			(clearance 0.1778)
			(thermal_gap 0.1778)
		)
		(pad "A80" thru_hole circle
			(at 69.34962 -3.24993 180)
			(size 1.0922 1.0922)
			(drill 0.7366)
			(layers "*.Cu" "*.Mask")
			(remove_unused_layers no)
			(net "GND")
			(clearance 0.1778)
			(thermal_gap 0.1778)
		)
		(pad "A81" thru_hole circle
			(at 70.35038 -1.24968 180)
			(size 1.0922 1.0922)
			(drill 0.7366)
			(layers "*.Cu" "*.Mask")
			(remove_unused_layers no)
			(net "P12V")
			(clearance 0.1778)
			(thermal_gap 0.1778)
		)
		(pad "A82" thru_hole circle
			(at 71.34987 -3.24993 180)
			(size 1.0922 1.0922)
			(drill 0.7366)
			(layers "*.Cu" "*.Mask")
			(remove_unused_layers no)
			(net "P12V")
			(clearance 0.1778)
			(thermal_gap 0.1778)
		)
		(pad "B1" thru_hole circle
			(at -11.64971 1.24968 180)
			(size 1.0922 1.0922)
			(drill 0.7366)
			(layers "*.Cu" "*.Mask")
			(remove_unused_layers no)
			(net "P12V")
			(clearance 0.1778)
			(thermal_gap 0.1778)
		)
		(pad "B2" thru_hole circle
			(at -10.65022 3.24993 180)
			(size 1.0922 1.0922)
			(drill 0.7366)
			(layers "*.Cu" "*.Mask")
			(remove_unused_layers no)
			(net "P12V")
			(clearance 0.1778)
			(thermal_gap 0.1778)
		)
		(pad "B3" thru_hole circle
			(at -9.64946 1.24968 180)
			(size 1.0922 1.0922)
			(drill 0.7366)
			(layers "*.Cu" "*.Mask")
			(remove_unused_layers no)
			(net "P12V")
			(clearance 0.1778)
			(thermal_gap 0.1778)
		)
		(pad "B4" thru_hole circle
			(at -8.64997 3.24993 180)
			(size 1.0922 1.0922)
			(drill 0.7366)
			(layers "*.Cu" "*.Mask")
			(remove_unused_layers no)
			(net "GND")
			(clearance 0.1778)
			(thermal_gap 0.1778)
		)
		(pad "B5" thru_hole circle
			(at -7.65048 1.24968 180)
			(size 1.0922 1.0922)
			(drill 0.7366)
			(layers "*.Cu" "*.Mask")
			(remove_unused_layers no)
			(net "BMC_I2C_CLK")
			(clearance 0.1778)
			(thermal_gap 0.1778)
		)
		(pad "B6" thru_hole circle
			(at -6.64972 3.24993 180)
			(size 1.0922 1.0922)
			(drill 0.7366)
			(layers "*.Cu" "*.Mask")
			(remove_unused_layers no)
			(net "BMC_I2C_DATA")
			(clearance 0.1778)
			(thermal_gap 0.1778)
		)
		(pad "B7" thru_hole circle
			(at -5.65023 1.24968 180)
			(size 1.0922 1.0922)
			(drill 0.7366)
			(layers "*.Cu" "*.Mask")
			(remove_unused_layers no)
			(net "GND")
			(clearance 0.1778)
			(thermal_gap 0.1778)
		)
		(pad "B8" thru_hole circle
			(at -4.64947 3.24993 180)
			(size 1.0922 1.0922)
			(drill 0.7366)
			(layers "*.Cu" "*.Mask")
			(remove_unused_layers no)
			(net "PMU_PWRBTN#")
			(clearance 0.1778)
			(thermal_gap 0.1778)
		)
		(pad "B9" thru_hole circle
			(at -3.64998 1.24968 180)
			(size 1.0922 1.0922)
			(drill 0.7366)
			(layers "*.Cu" "*.Mask")
			(remove_unused_layers no)
			(net "USB_P1_DP")
			(clearance 0.1778)
			(thermal_gap 0.1778)
		)
		(pad "B10" thru_hole circle
			(at -2.65049 3.24993 180)
			(size 1.0922 1.0922)
			(drill 0.7366)
			(layers "*.Cu" "*.Mask")
			(remove_unused_layers no)
			(net "USB_P1_DN")
			(clearance 0.1778)
			(thermal_gap 0.1778)
		)
		(pad "B11" thru_hole circle
			(at -1.64973 1.24968 180)
			(size 1.0922 1.0922)
			(drill 0.7366)
			(layers "*.Cu" "*.Mask")
			(remove_unused_layers no)
			(net "BMC_SYS_RESET#")
			(clearance 0.1778)
			(thermal_gap 0.1778)
		)
		(pad "B12" thru_hole circle
			(at 1.35001 3.24993 180)
			(size 1.0922 1.0922)
			(drill 0.7366)
			(layers "*.Cu" "*.Mask")
			(remove_unused_layers no)
			(net "BMC_I2C_ALERT#")
			(clearance 0.1778)
			(thermal_gap 0.1778)
		)
		(pad "B13" thru_hole circle
			(at 2.3495 1.24968 180)
			(size 1.0922 1.0922)
			(drill 0.7366)
			(layers "*.Cu" "*.Mask")
			(remove_unused_layers no)
			(net "GND")
			(clearance 0.1778)
			(thermal_gap 0.1778)
		)
		(pad "B14" thru_hole circle
			(at 3.35026 3.24993 180)
			(size 1.0922 1.0922)
			(drill 0.7366)
			(layers "*.Cu" "*.Mask")
			(remove_unused_layers no)
			(net "GND")
			(clearance 0.1778)
			(thermal_gap 0.1778)
		)
		(pad "B15" thru_hole circle
			(at 4.34975 1.24968 180)
			(size 1.0922 1.0922)
			(drill 0.7366)
			(layers "*.Cu" "*.Mask")
			(remove_unused_layers no)
			(net "P2E_CPU_SAS_TX_DP0")
			(clearance 0.1778)
			(thermal_gap 0.1778)
		)
		(pad "B16" thru_hole circle
			(at 5.35051 3.24993 180)
			(size 1.0922 1.0922)
			(drill 0.7366)
			(layers "*.Cu" "*.Mask")
			(remove_unused_layers no)
			(net "P2E_CPU_SAS_TX_DN0")
			(clearance 0.1778)
			(thermal_gap 0.1778)
		)
		(pad "B17" thru_hole circle
			(at 6.35 1.24968 180)
			(size 1.0922 1.0922)
			(drill 0.7366)
			(layers "*.Cu" "*.Mask")
			(remove_unused_layers no)
			(net "GND")
			(clearance 0.1778)
			(thermal_gap 0.1778)
		)
		(pad "B18" thru_hole circle
			(at 7.34949 3.24993 180)
			(size 1.0922 1.0922)
			(drill 0.7366)
			(layers "*.Cu" "*.Mask")
			(remove_unused_layers no)
			(net "GND")
			(clearance 0.1778)
			(thermal_gap 0.1778)
		)
		(pad "B19" thru_hole circle
			(at 8.35025 1.24968 180)
			(size 1.0922 1.0922)
			(drill 0.7366)
			(layers "*.Cu" "*.Mask")
			(remove_unused_layers no)
			(net "P2E_CPU_SAS_TX_DP1")
			(clearance 0.1778)
			(thermal_gap 0.1778)
		)
		(pad "B20" thru_hole circle
			(at 9.34974 3.24993 180)
			(size 1.0922 1.0922)
			(drill 0.7366)
			(layers "*.Cu" "*.Mask")
			(remove_unused_layers no)
			(net "P2E_CPU_SAS_TX_DN1")
			(clearance 0.1778)
			(thermal_gap 0.1778)
		)
		(pad "B21" thru_hole circle
			(at 10.3505 1.24968 180)
			(size 1.0922 1.0922)
			(drill 0.7366)
			(layers "*.Cu" "*.Mask")
			(remove_unused_layers no)
			(net "GND")
			(clearance 0.1778)
			(thermal_gap 0.1778)
		)
		(pad "B22" thru_hole circle
			(at 11.34999 3.24993 180)
			(size 1.0922 1.0922)
			(drill 0.7366)
			(layers "*.Cu" "*.Mask")
			(remove_unused_layers no)
			(net "GND")
			(clearance 0.1778)
			(thermal_gap 0.1778)
		)
		(pad "B23" thru_hole circle
			(at 12.34948 1.24968 180)
			(size 1.0922 1.0922)
			(drill 0.7366)
			(layers "*.Cu" "*.Mask")
			(remove_unused_layers no)
			(net "P2E_CPU_SAS_TX_DP2")
			(clearance 0.1778)
			(thermal_gap 0.1778)
		)
		(pad "B24" thru_hole circle
			(at 13.35024 3.24993 180)
			(size 1.0922 1.0922)
			(drill 0.7366)
			(layers "*.Cu" "*.Mask")
			(remove_unused_layers no)
			(net "P2E_CPU_SAS_TX_DN2")
			(clearance 0.1778)
			(thermal_gap 0.1778)
		)
		(pad "B25" thru_hole circle
			(at 14.34973 1.24968 180)
			(size 1.0922 1.0922)
			(drill 0.7366)
			(layers "*.Cu" "*.Mask")
			(remove_unused_layers no)
			(net "GND")
			(clearance 0.1778)
			(thermal_gap 0.1778)
		)
		(pad "B26" thru_hole circle
			(at 15.35049 3.24993 180)
			(size 1.0922 1.0922)
			(drill 0.7366)
			(layers "*.Cu" "*.Mask")
			(remove_unused_layers no)
			(net "GND")
			(clearance 0.1778)
			(thermal_gap 0.1778)
		)
		(pad "B27" thru_hole circle
			(at 16.34998 1.24968 180)
			(size 1.0922 1.0922)
			(drill 0.7366)
			(layers "*.Cu" "*.Mask")
			(remove_unused_layers no)
			(net "P2E_CPU_SAS_TX_DP3")
			(clearance 0.1778)
			(thermal_gap 0.1778)
		)
		(pad "B28" thru_hole circle
			(at 17.34947 3.24993 180)
			(size 1.0922 1.0922)
			(drill 0.7366)
			(layers "*.Cu" "*.Mask")
			(remove_unused_layers no)
			(net "P2E_CPU_SAS_TX_DN3")
			(clearance 0.1778)
			(thermal_gap 0.1778)
		)
		(pad "B29" thru_hole circle
			(at 18.35023 1.24968 180)
			(size 1.0922 1.0922)
			(drill 0.7366)
			(layers "*.Cu" "*.Mask")
			(remove_unused_layers no)
			(net "GND")
			(clearance 0.1778)
			(thermal_gap 0.1778)
		)
		(pad "B30" thru_hole circle
			(at 19.34972 3.24993 180)
			(size 1.0922 1.0922)
			(drill 0.7366)
			(layers "*.Cu" "*.Mask")
			(remove_unused_layers no)
			(net "GND")
			(clearance 0.1778)
			(thermal_gap 0.1778)
		)
		(pad "B31" thru_hole circle
			(at 20.35048 1.24968 180)
			(size 1.0922 1.0922)
			(drill 0.7366)
			(layers "*.Cu" "*.Mask")
			(remove_unused_layers no)
			(net "SATA2_TX_C_DP0")
			(clearance 0.1778)
			(thermal_gap 0.1778)
		)
		(pad "B32" thru_hole circle
			(at 21.34997 3.24993 180)
			(size 1.0922 1.0922)
			(drill 0.7366)
			(layers "*.Cu" "*.Mask")
			(remove_unused_layers no)
			(net "SATA2_TX_C_DN0")
			(clearance 0.1778)
			(thermal_gap 0.1778)
		)
		(pad "B33" thru_hole circle
			(at 22.34946 1.24968 180)
			(size 1.0922 1.0922)
			(drill 0.7366)
			(layers "*.Cu" "*.Mask")
			(remove_unused_layers no)
			(net "GND")
			(clearance 0.1778)
			(thermal_gap 0.1778)
		)
		(pad "B34" thru_hole circle
			(at 23.35022 3.24993 180)
			(size 1.0922 1.0922)
			(drill 0.7366)
			(layers "*.Cu" "*.Mask")
			(remove_unused_layers no)
			(net "GND")
			(clearance 0.1778)
			(thermal_gap 0.1778)
		)
		(pad "B35" thru_hole circle
			(at 24.34971 1.24968 180)
			(size 1.0922 1.0922)
			(drill 0.7366)
			(layers "*.Cu" "*.Mask")
			(remove_unused_layers no)
			(net "CLK_100M_CLKBUFF_ENET_DP")
			(clearance 0.1778)
			(thermal_gap 0.1778)
		)
		(pad "B36" thru_hole circle
			(at 25.35047 3.24993 180)
			(size 1.0922 1.0922)
			(drill 0.7366)
			(layers "*.Cu" "*.Mask")
			(remove_unused_layers no)
			(net "CLK_100M_CLKBUFF_ENET_DN")
			(clearance 0.1778)
			(thermal_gap 0.1778)
		)
		(pad "B37" thru_hole circle
			(at 26.34996 1.24968 180)
			(size 1.0922 1.0922)
			(drill 0.7366)
			(layers "*.Cu" "*.Mask")
			(remove_unused_layers no)
			(net "GND")
			(clearance 0.1778)
			(thermal_gap 0.1778)
		)
		(pad "B38" thru_hole circle
			(at 27.34945 3.24993 180)
			(size 1.0922 1.0922)
			(drill 0.7366)
			(layers "*.Cu" "*.Mask")
			(remove_unused_layers no)
			(net "GND")
			(clearance 0.1778)
			(thermal_gap 0.1778)
		)
		(pad "B39" thru_hole circle
			(at 28.35021 1.24968 180)
			(size 1.0922 1.0922)
			(drill 0.7366)
			(layers "*.Cu" "*.Mask")
			(remove_unused_layers no)
			(net "PCIE1_RESET#")
			(clearance 0.1778)
			(thermal_gap 0.1778)
		)
		(pad "B40" thru_hole circle
			(at 29.3497 3.24993 180)
			(size 1.0922 1.0922)
			(drill 0.7366)
			(layers "*.Cu" "*.Mask")
			(remove_unused_layers no)
			(net "PCIE_RSVD_B40")
			(clearance 0.1778)
			(thermal_gap 0.1778)
		)
		(pad "B41" thru_hole circle
			(at 30.35046 1.24968 180)
			(size 1.0922 1.0922)
			(drill 0.7366)
			(layers "*.Cu" "*.Mask")
			(remove_unused_layers no)
			(net "GND")
			(clearance 0.1778)
			(thermal_gap 0.1778)
		)
		(pad "B42" thru_hole circle
			(at 31.34995 3.24993 180)
			(size 1.0922 1.0922)
			(drill 0.7366)
			(layers "*.Cu" "*.Mask")
			(remove_unused_layers no)
			(net "GND")
			(clearance 0.1778)
			(thermal_gap 0.1778)
		)
		(pad "B43" thru_hole circle
			(at 32.34944 1.24968 180)
			(size 1.0922 1.0922)
			(drill 0.7366)
			(layers "*.Cu" "*.Mask")
			(remove_unused_layers no)
			(net "GBE_SMBCLK_R")
			(clearance 0.1778)
			(thermal_gap 0.1778)
		)
		(pad "B44" thru_hole circle
			(at 33.3502 3.24993 180)
			(size 1.0922 1.0922)
			(drill 0.7366)
			(layers "*.Cu" "*.Mask")
			(remove_unused_layers no)
			(net "GBE_SMDATA_R")
			(clearance 0.1778)
			(thermal_gap 0.1778)
		)
		(pad "B45" thru_hole circle
			(at 34.34969 1.24968 180)
			(size 1.0922 1.0922)
			(drill 0.7366)
			(layers "*.Cu" "*.Mask")
			(remove_unused_layers no)
			(net "GND")
			(clearance 0.1778)
			(thermal_gap 0.1778)
		)
		(pad "B46" thru_hole circle
			(at 35.35045 3.24993 180)
			(size 1.0922 1.0922)
			(drill 0.7366)
			(layers "*.Cu" "*.Mask")
			(remove_unused_layers no)
			(net "GND")
			(clearance 0.1778)
			(thermal_gap 0.1778)
		)
		(pad "B47" thru_hole circle
			(at 36.34994 1.24968 180)
			(size 1.0922 1.0922)
			(drill 0.7366)
			(layers "*.Cu" "*.Mask")
			(remove_unused_layers no)
			(net "CPU_GBE_TX_C_DP0")
			(clearance 0.1778)
			(thermal_gap 0.1778)
		)
		(pad "B48" thru_hole circle
			(at 37.34943 3.24993 180)
			(size 1.0922 1.0922)
			(drill 0.7366)
			(layers "*.Cu" "*.Mask")
			(remove_unused_layers no)
			(net "CPU_GBE_TX_C_DN0")
			(clearance 0.1778)
			(thermal_gap 0.1778)
		)
		(pad "B49" thru_hole circle
			(at 38.35019 1.24968 180)
			(size 1.0922 1.0922)
			(drill 0.7366)
			(layers "*.Cu" "*.Mask")
			(remove_unused_layers no)
			(net "GND")
			(clearance 0.1778)
			(thermal_gap 0.1778)
		)
		(pad "B50" thru_hole circle
			(at 39.34968 3.24993 180)
			(size 1.0922 1.0922)
			(drill 0.7366)
			(layers "*.Cu" "*.Mask")
			(remove_unused_layers no)
			(net "GND")
			(clearance 0.1778)
			(thermal_gap 0.1778)
		)
		(pad "B51" thru_hole circle
			(at 40.35044 1.24968 180)
			(size 1.0922 1.0922)
			(drill 0.7366)
			(layers "*.Cu" "*.Mask")
			(remove_unused_layers no)
			(net "P2E_CPU_SAS_TX_DP4")
			(clearance 0.1778)
			(thermal_gap 0.1778)
		)
		(pad "B52" thru_hole circle
			(at 41.34993 3.24993 180)
			(size 1.0922 1.0922)
			(drill 0.7366)
			(layers "*.Cu" "*.Mask")
			(remove_unused_layers no)
			(net "P2E_CPU_SAS_TX_DN4")
			(clearance 0.1778)
			(thermal_gap 0.1778)
		)
		(pad "B53" thru_hole circle
			(at 42.34942 1.24968 180)
			(size 1.0922 1.0922)
			(drill 0.7366)
			(layers "*.Cu" "*.Mask")
			(remove_unused_layers no)
			(net "GND")
			(clearance 0.1778)
			(thermal_gap 0.1778)
		)
		(pad "B54" thru_hole circle
			(at 43.35018 3.24993 180)
			(size 1.0922 1.0922)
			(drill 0.7366)
			(layers "*.Cu" "*.Mask")
			(remove_unused_layers no)
			(net "GND")
			(clearance 0.1778)
			(thermal_gap 0.1778)
		)
		(pad "B55" thru_hole circle
			(at 44.34967 1.24968 180)
			(size 1.0922 1.0922)
			(drill 0.7366)
			(layers "*.Cu" "*.Mask")
			(remove_unused_layers no)
			(net "P2E_CPU_SAS_TX_DP5")
			(clearance 0.1778)
			(thermal_gap 0.1778)
		)
		(pad "B56" thru_hole circle
			(at 45.35043 3.24993 180)
			(size 1.0922 1.0922)
			(drill 0.7366)
			(layers "*.Cu" "*.Mask")
			(remove_unused_layers no)
			(net "P2E_CPU_SAS_TX_DN5")
			(clearance 0.1778)
			(thermal_gap 0.1778)
		)
		(pad "B57" thru_hole circle
			(at 46.34992 1.24968 180)
			(size 1.0922 1.0922)
			(drill 0.7366)
			(layers "*.Cu" "*.Mask")
			(remove_unused_layers no)
			(net "GND")
			(clearance 0.1778)
			(thermal_gap 0.1778)
		)
		(pad "B58" thru_hole circle
			(at 47.34941 3.24993 180)
			(size 1.0922 1.0922)
			(drill 0.7366)
			(layers "*.Cu" "*.Mask")
			(remove_unused_layers no)
			(net "GND")
			(clearance 0.1778)
			(thermal_gap 0.1778)
		)
		(pad "B59" thru_hole circle
			(at 48.35017 1.24968 180)
			(size 1.0922 1.0922)
			(drill 0.7366)
			(layers "*.Cu" "*.Mask")
			(remove_unused_layers no)
			(net "P2E_CPU_SAS_TX_DP6")
			(clearance 0.1778)
			(thermal_gap 0.1778)
		)
		(pad "B60" thru_hole circle
			(at 49.34966 3.24993 180)
			(size 1.0922 1.0922)
			(drill 0.7366)
			(layers "*.Cu" "*.Mask")
			(remove_unused_layers no)
			(net "P2E_CPU_SAS_TX_DN6")
			(clearance 0.1778)
			(thermal_gap 0.1778)
		)
		(pad "B61" thru_hole circle
			(at 50.35042 1.24968 180)
			(size 1.0922 1.0922)
			(drill 0.7366)
			(layers "*.Cu" "*.Mask")
			(remove_unused_layers no)
			(net "GND")
			(clearance 0.1778)
			(thermal_gap 0.1778)
		)
		(pad "B62" thru_hole circle
			(at 51.34991 3.24993 180)
			(size 1.0922 1.0922)
			(drill 0.7366)
			(layers "*.Cu" "*.Mask")
			(remove_unused_layers no)
			(net "GND")
			(clearance 0.1778)
			(thermal_gap 0.1778)
		)
		(pad "B63" thru_hole circle
			(at 52.3494 1.24968 180)
			(size 1.0922 1.0922)
			(drill 0.7366)
			(layers "*.Cu" "*.Mask")
			(remove_unused_layers no)
			(net "P2E_CPU_SAS_TX_DP7")
			(clearance 0.1778)
			(thermal_gap 0.1778)
		)
		(pad "B64" thru_hole circle
			(at 53.35016 3.24993 180)
			(size 1.0922 1.0922)
			(drill 0.7366)
			(layers "*.Cu" "*.Mask")
			(remove_unused_layers no)
			(net "P2E_CPU_SAS_TX_DN7")
			(clearance 0.1778)
			(thermal_gap 0.1778)
		)
		(pad "B65" thru_hole circle
			(at 54.34965 1.24968 180)
			(size 1.0922 1.0922)
			(drill 0.7366)
			(layers "*.Cu" "*.Mask")
			(remove_unused_layers no)
			(net "GND")
			(clearance 0.1778)
			(thermal_gap 0.1778)
		)
		(pad "B66" thru_hole circle
			(at 55.35041 3.24993 180)
			(size 1.0922 1.0922)
			(drill 0.7366)
			(layers "*.Cu" "*.Mask")
			(remove_unused_layers no)
			(net "GND")
			(clearance 0.1778)
			(thermal_gap 0.1778)
		)
		(pad "B67" thru_hole circle
			(at 56.3499 1.24968 180)
			(size 1.0922 1.0922)
			(drill 0.7366)
			(layers "*.Cu" "*.Mask")
			(remove_unused_layers no)
			(net "P2E_CPU_ETH10G_TX_DP8")
			(clearance 0.1778)
			(thermal_gap 0.1778)
		)
		(pad "B68" thru_hole circle
			(at 57.34939 3.24993 180)
			(size 1.0922 1.0922)
			(drill 0.7366)
			(layers "*.Cu" "*.Mask")
			(remove_unused_layers no)
			(net "P2E_CPU_ETH10G_TX_DN8")
			(clearance 0.1778)
			(thermal_gap 0.1778)
		)
	)
)
